(kicad_pcb
	(version 20260206)
	(generator "pcbnew")
	(generator_version "10.0")
	(general
		(thickness 1.6)
		(legacy_teardrops no)
	)
	(paper "A4")
	(title_block
		(title "9054_F0T_PDB_BD_GPU_F_V04_1213_1550_OCP.brd")
		(comment 1 "Grand Teton / footprints 131-136 of 608")
	)
	(layers
		(0 "F.Cu" signal "TOP")
		(4 "In1.Cu" signal "GND")
		(6 "In2.Cu" signal "IN1")
		(8 "In3.Cu" signal "GND1")
		(10 "In4.Cu" signal "VCC")
		(12 "In5.Cu" signal "VCC1")
		(14 "In6.Cu" signal "GND2")
		(16 "In7.Cu" signal "IN2")
		(18 "In8.Cu" signal "GND3")
		(2 "B.Cu" signal "BOTTOM")
		(9 "F.Adhes" user "F.Adhesive")
		(11 "B.Adhes" user "B.Adhesive")
		(13 "F.Paste" user "Package Geometry/Pastemask Top")
		(15 "B.Paste" user "Package Geometry/Pastemask Bottom")
		(5 "F.SilkS" user "Ref Des/Silkscreen Top")
		(7 "B.SilkS" user "Ref Des/Silkscreen Bottom")
		(1 "F.Mask" user "Board Geometry/Soldermask Top")
		(3 "B.Mask" user "Board Geometry/Soldermask Bottom")
		(17 "Dwgs.User" user "User.Drawings")
		(19 "Cmts.User" user "User.Comments")
		(21 "Eco1.User" user "User.Eco1")
		(23 "Eco2.User" user "User.Eco2")
		(25 "Edge.Cuts" user "Board Geometry/Outline")
		(27 "Margin" user)
		(31 "F.CrtYd" user "Package Geometry/Place Bound Top")
		(29 "B.CrtYd" user "Package Geometry/Place Bound Bottom")
		(35 "F.Fab" user "Ref Des/Assembly Top")
		(33 "B.Fab" user "Ref Des/Assembly Bottom")
	)
	(footprint ""
		(layer "F.Cu")
		(at 436.753 -38.862)
		(property "Reference" "R10"
			(at 0 0 0)
			(layer "F.SilkS")
			(hide yes)
			(effects
				(font
					(size 1.27 1.27)
				)
			)
		)
		(property "Value" ""
			(at 0 0 0)
			(layer "F.Fab")
			(effects
				(font
					(size 1.27 1.27)
				)
			)
		)
		(duplicate_pad_numbers_are_jumpers no)
		(fp_line
			(start -0.7874 -0.4064)
			(end 0.7874 -0.4064)
			(stroke
				(width 0.1524)
				(type default)
			)
			(layer "F.SilkS")
		)
		(fp_line
			(start -0.7874 0.4064)
			(end -0.7874 -0.4064)
			(stroke
				(width 0.1524)
				(type default)
			)
			(layer "F.SilkS")
		)
		(fp_line
			(start 0.7874 -0.4064)
			(end 0.7874 0.4064)
			(stroke
				(width 0.1524)
				(type default)
			)
			(layer "F.SilkS")
		)
		(fp_line
			(start 0.7874 0.4064)
			(end -0.7874 0.4064)
			(stroke
				(width 0.1524)
				(type default)
			)
			(layer "F.SilkS")
		)
		(fp_line
			(start -0.67945 -0.305054)
			(end -0.12065 -0.305054)
			(stroke
				(width 0.1)
				(type default)
			)
			(layer "F.Fab")
		)
		(fp_line
			(start -0.67945 0.3048)
			(end -0.67945 -0.305054)
			(stroke
				(width 0.1)
				(type default)
			)
			(layer "F.Fab")
		)
		(fp_line
			(start -0.12065 -0.305054)
			(end -0.12065 -0.2794)
			(stroke
				(width 0.1)
				(type default)
			)
			(layer "F.Fab")
		)
		(fp_line
			(start -0.12065 -0.2794)
			(end 0.12065 -0.2794)
			(stroke
				(width 0.1)
				(type default)
			)
			(layer "F.Fab")
		)
		(fp_line
			(start -0.12065 0.2794)
			(end -0.12065 0.3048)
			(stroke
				(width 0.1)
				(type default)
			)
			(layer "F.Fab")
		)
		(fp_line
			(start -0.12065 0.3048)
			(end -0.67945 0.3048)
			(stroke
				(width 0.1)
				(type default)
			)
			(layer "F.Fab")
		)
		(fp_line
			(start 0.120396 0.2794)
			(end -0.12065 0.2794)
			(stroke
				(width 0.1)
				(type default)
			)
			(layer "F.Fab")
		)
		(fp_line
			(start 0.120396 0.3048)
			(end 0.120396 0.2794)
			(stroke
				(width 0.1)
				(type default)
			)
			(layer "F.Fab")
		)
		(fp_line
			(start 0.12065 -0.3048)
			(end 0.67945 -0.3048)
			(stroke
				(width 0.1)
				(type default)
			)
			(layer "F.Fab")
		)
		(fp_line
			(start 0.12065 -0.2794)
			(end 0.12065 -0.3048)
			(stroke
				(width 0.1)
				(type default)
			)
			(layer "F.Fab")
		)
		(fp_line
			(start 0.67945 -0.3048)
			(end 0.67945 0.3048)
			(stroke
				(width 0.1)
				(type default)
			)
			(layer "F.Fab")
		)
		(fp_line
			(start 0.67945 0.3048)
			(end 0.120396 0.3048)
			(stroke
				(width 0.1)
				(type default)
			)
			(layer "F.Fab")
		)
		(pad "1" smd circle
			(at -0.40005 0)
			(size 0 0)
			(layers "F.Cu" "F.Mask" "F.Paste")
			(net "PWRGD_P3V3_AUX_MB_BUF")
		)
		(pad "2" smd circle
			(at 0.40005 0)
			(size 0 0)
			(layers "F.Cu" "F.Mask" "F.Paste")
			(net "MB_P52V_I2C_EN")
		)
	)
	(footprint ""
		(layer "F.Cu")
		(at 427.228 -37.592)
		(property "Reference" "R138"
			(at 0 0 0)
			(layer "F.SilkS")
			(hide yes)
			(effects
				(font
					(size 1.27 1.27)
				)
			)
		)
		(property "Value" ""
			(at 0 0 0)
			(layer "F.Fab")
			(effects
				(font
					(size 1.27 1.27)
				)
			)
		)
		(duplicate_pad_numbers_are_jumpers no)
		(fp_line
			(start -0.7874 -0.4064)
			(end 0.7874 -0.4064)
			(stroke
				(width 0.1524)
				(type default)
			)
			(layer "F.SilkS")
		)
		(fp_line
			(start -0.7874 0.4064)
			(end -0.7874 -0.4064)
			(stroke
				(width 0.1524)
				(type default)
			)
			(layer "F.SilkS")
		)
		(fp_line
			(start 0.7874 -0.4064)
			(end 0.7874 0.4064)
			(stroke
				(width 0.1524)
				(type default)
			)
			(layer "F.SilkS")
		)
		(fp_line
			(start 0.7874 0.4064)
			(end -0.7874 0.4064)
			(stroke
				(width 0.1524)
				(type default)
			)
			(layer "F.SilkS")
		)
		(fp_line
			(start -0.67945 -0.305054)
			(end -0.12065 -0.305054)
			(stroke
				(width 0.1)
				(type default)
			)
			(layer "F.Fab")
		)
		(fp_line
			(start -0.67945 0.3048)
			(end -0.67945 -0.305054)
			(stroke
				(width 0.1)
				(type default)
			)
			(layer "F.Fab")
		)
		(fp_line
			(start -0.12065 -0.305054)
			(end -0.12065 -0.2794)
			(stroke
				(width 0.1)
				(type default)
			)
			(layer "F.Fab")
		)
		(fp_line
			(start -0.12065 -0.2794)
			(end 0.12065 -0.2794)
			(stroke
				(width 0.1)
				(type default)
			)
			(layer "F.Fab")
		)
		(fp_line
			(start -0.12065 0.2794)
			(end -0.12065 0.3048)
			(stroke
				(width 0.1)
				(type default)
			)
			(layer "F.Fab")
		)
		(fp_line
			(start -0.12065 0.3048)
			(end -0.67945 0.3048)
			(stroke
				(width 0.1)
				(type default)
			)
			(layer "F.Fab")
		)
		(fp_line
			(start 0.120396 0.2794)
			(end -0.12065 0.2794)
			(stroke
				(width 0.1)
				(type default)
			)
			(layer "F.Fab")
		)
		(fp_line
			(start 0.120396 0.3048)
			(end 0.120396 0.2794)
			(stroke
				(width 0.1)
				(type default)
			)
			(layer "F.Fab")
		)
		(fp_line
			(start 0.12065 -0.3048)
			(end 0.67945 -0.3048)
			(stroke
				(width 0.1)
				(type default)
			)
			(layer "F.Fab")
		)
		(fp_line
			(start 0.12065 -0.2794)
			(end 0.12065 -0.3048)
			(stroke
				(width 0.1)
				(type default)
			)
			(layer "F.Fab")
		)
		(fp_line
			(start 0.67945 -0.3048)
			(end 0.67945 0.3048)
			(stroke
				(width 0.1)
				(type default)
			)
			(layer "F.Fab")
		)
		(fp_line
			(start 0.67945 0.3048)
			(end 0.120396 0.3048)
			(stroke
				(width 0.1)
				(type default)
			)
			(layer "F.Fab")
		)
		(pad "1" smd circle
			(at -0.40005 0)
			(size 0 0)
			(layers "F.Cu" "F.Mask" "F.Paste")
			(net "BOARD_ID_0")
		)
		(pad "2" smd circle
			(at 0.40005 0)
			(size 0 0)
			(layers "F.Cu" "F.Mask" "F.Paste")
			(net "GND")
		)
	)
	(footprint ""
		(layer "F.Cu")
		(at 323.13626 -18.2626 180)
		(property "Reference" "PQ36"
			(at -9.628886 -3.917188 0)
			(unlocked yes)
			(layer "F.SilkS")
			(effects
				(font
					(size 0.7874 0.5842)
					(thickness 0.1524)
				)
				(justify left)
			)
		)
		(property "Value" ""
			(at 0 0 180)
			(layer "F.Fab")
			(effects
				(font
					(size 1.27 1.27)
				)
			)
		)
		(duplicate_pad_numbers_are_jumpers no)
		(fp_line
			(start 7.649972 4.99999)
			(end 7.649972 -4.99999)
			(stroke
				(width 0.1524)
				(type default)
			)
			(layer "F.SilkS")
		)
		(fp_line
			(start 7.649972 -4.99999)
			(end 7.630414 -4.99999)
			(stroke
				(width 0.1524)
				(type default)
			)
			(layer "F.SilkS")
		)
		(fp_line
			(start 7.630414 4.99999)
			(end 7.649972 4.99999)
			(stroke
				(width 0.1524)
				(type default)
			)
			(layer "F.SilkS")
		)
		(fp_line
			(start 5.115814 -4.99999)
			(end -7.649972 -4.99999)
			(stroke
				(width 0.1524)
				(type default)
			)
			(layer "F.SilkS")
		)
		(fp_line
			(start -7.649972 4.99999)
			(end 5.115814 4.99999)
			(stroke
				(width 0.1524)
				(type default)
			)
			(layer "F.SilkS")
		)
		(fp_line
			(start -7.649972 3.3274)
			(end -7.649972 4.99999)
			(stroke
				(width 0.1524)
				(type default)
			)
			(layer "F.SilkS")
		)
		(fp_line
			(start -7.649972 -1.7526)
			(end -7.649972 1.7526)
			(stroke
				(width 0.1524)
				(type default)
			)
			(layer "F.SilkS")
		)
		(fp_line
			(start -7.649972 -4.99999)
			(end -7.649972 -3.3274)
			(stroke
				(width 0.1524)
				(type default)
			)
			(layer "F.SilkS")
		)
		(fp_line
			(start 7.649972 4.99999)
			(end 7.649972 -4.99999)
			(stroke
				(width 0.1)
				(type default)
			)
			(layer "F.Fab")
		)
		(fp_line
			(start 7.649972 -4.99999)
			(end -7.649972 -4.99999)
			(stroke
				(width 0.1)
				(type default)
			)
			(layer "F.Fab")
		)
		(fp_line
			(start -7.649972 4.99999)
			(end 7.649972 4.99999)
			(stroke
				(width 0.1)
				(type default)
			)
			(layer "F.Fab")
		)
		(fp_line
			(start -7.649972 -4.99999)
			(end -7.649972 4.99999)
			(stroke
				(width 0.1)
				(type default)
			)
			(layer "F.Fab")
		)
		(pad "D" smd circle
			(at 2.15011 0 180)
			(size 0 0)
			(layers "F.Cu" "F.Mask" "F.Paste")
			(net "P52V_HS1_DRAIN_2")
		)
		(pad "G" smd rect
			(at -7.050024 -2.54 90)
			(size 1.3208 3.0988)
			(layers "F.Cu" "F.Mask" "F.Paste")
			(net "P52V_HS1_GATE5")
		)
		(pad "S" smd rect
			(at -7.050024 2.54 90)
			(size 1.3208 3.0988)
			(layers "F.Cu" "F.Mask" "F.Paste")
			(net "P52V_HS1")
		)
		(zone
			(layer "F.Cu")
			(hatch none 0.5)
			(connect_pads
				(clearance 0)
			)
			(min_thickness 0.25)
			(keepout
				(tracks not_allowed)
				(vias allowed)
				(pads allowed)
				(copperpour not_allowed)
				(footprints allowed)
			)
			(placement
				(enabled no)
				(sheetname "")
			)
			(fill
				(thermal_gap 0.5)
				(thermal_bridge_width 0.5)
				(island_removal_mode 0)
			)
			(polygon
				(pts
					(xy 317.95466 -13.2842) (xy 330.78166 -13.2842) (xy 330.78166 -15.0114) (xy 328.57186 -15.0114)
					(xy 328.57186 -16.4338) (xy 330.78166 -16.4338) (xy 330.78166 -20.0914) (xy 328.57186 -20.0914)
					(xy 328.57186 -21.5138) (xy 330.78166 -21.5138) (xy 330.78166 -23.241) (xy 317.95466 -23.241) (xy 317.95466 -22.0726)
					(xy 324.15226 -22.0726) (xy 324.15226 -14.4526) (xy 317.95466 -14.4526)
				)
			)
		)
	)
	(footprint ""
		(layer "F.Cu")
		(at 318.008 -85.598 180)
		(property "Reference" "PR6967"
			(at 0 0 180)
			(layer "F.SilkS")
			(hide yes)
			(effects
				(font
					(size 1.27 1.27)
				)
			)
		)
		(property "Value" ""
			(at 0 0 180)
			(layer "F.Fab")
			(effects
				(font
					(size 1.27 1.27)
				)
			)
		)
		(duplicate_pad_numbers_are_jumpers no)
		(fp_line
			(start 0.7874 0.4064)
			(end -0.7874 0.4064)
			(stroke
				(width 0.1524)
				(type default)
			)
			(layer "F.SilkS")
		)
		(fp_line
			(start 0.7874 -0.4064)
			(end 0.7874 0.4064)
			(stroke
				(width 0.1524)
				(type default)
			)
			(layer "F.SilkS")
		)
		(fp_line
			(start -0.7874 0.4064)
			(end -0.7874 -0.4064)
			(stroke
				(width 0.1524)
				(type default)
			)
			(layer "F.SilkS")
		)
		(fp_line
			(start -0.7874 -0.4064)
			(end 0.7874 -0.4064)
			(stroke
				(width 0.1524)
				(type default)
			)
			(layer "F.SilkS")
		)
		(fp_line
			(start 0.67945 0.3048)
			(end 0.120396 0.3048)
			(stroke
				(width 0.1)
				(type default)
			)
			(layer "F.Fab")
		)
		(fp_line
			(start 0.67945 -0.3048)
			(end 0.67945 0.3048)
			(stroke
				(width 0.1)
				(type default)
			)
			(layer "F.Fab")
		)
		(fp_line
			(start 0.12065 -0.2794)
			(end 0.12065 -0.3048)
			(stroke
				(width 0.1)
				(type default)
			)
			(layer "F.Fab")
		)
		(fp_line
			(start 0.12065 -0.3048)
			(end 0.67945 -0.3048)
			(stroke
				(width 0.1)
				(type default)
			)
			(layer "F.Fab")
		)
		(fp_line
			(start 0.120396 0.3048)
			(end 0.120396 0.2794)
			(stroke
				(width 0.1)
				(type default)
			)
			(layer "F.Fab")
		)
		(fp_line
			(start 0.120396 0.2794)
			(end -0.12065 0.2794)
			(stroke
				(width 0.1)
				(type default)
			)
			(layer "F.Fab")
		)
		(fp_line
			(start -0.12065 0.3048)
			(end -0.67945 0.3048)
			(stroke
				(width 0.1)
				(type default)
			)
			(layer "F.Fab")
		)
		(fp_line
			(start -0.12065 0.2794)
			(end -0.12065 0.3048)
			(stroke
				(width 0.1)
				(type default)
			)
			(layer "F.Fab")
		)
		(fp_line
			(start -0.12065 -0.2794)
			(end 0.12065 -0.2794)
			(stroke
				(width 0.1)
				(type default)
			)
			(layer "F.Fab")
		)
		(fp_line
			(start -0.12065 -0.305054)
			(end -0.12065 -0.2794)
			(stroke
				(width 0.1)
				(type default)
			)
			(layer "F.Fab")
		)
		(fp_line
			(start -0.67945 0.3048)
			(end -0.67945 -0.305054)
			(stroke
				(width 0.1)
				(type default)
			)
			(layer "F.Fab")
		)
		(fp_line
			(start -0.67945 -0.305054)
			(end -0.12065 -0.305054)
			(stroke
				(width 0.1)
				(type default)
			)
			(layer "F.Fab")
		)
		(pad "1" smd rect
			(at -0.40005 0)
			(size 0.4572 0.508)
			(layers "F.Cu" "F.Mask" "F.Paste")
			(net "P52V_HS1_TEMPP")
		)
		(pad "2" smd rect
			(at 0.40005 0)
			(size 0.4572 0.508)
			(layers "F.Cu" "F.Mask" "F.Paste")
			(net "P52V_HS1_TEMP_R")
		)
	)
	(footprint ""
		(layer "F.Cu")
		(at 334.631284 -27.7876 -90)
		(property "Reference" "PR477"
			(at 0 0 270)
			(layer "F.SilkS")
			(hide yes)
			(effects
				(font
					(size 1.27 1.27)
				)
			)
		)
		(property "Value" ""
			(at 0 0 270)
			(layer "F.Fab")
			(effects
				(font
					(size 1.27 1.27)
				)
			)
		)
		(duplicate_pad_numbers_are_jumpers no)
		(fp_line
			(start -1.2954 0.5842)
			(end -1.2954 -0.5842)
			(stroke
				(width 0.1524)
				(type default)
			)
			(layer "F.SilkS")
		)
		(fp_line
			(start 1.2954 0.5842)
			(end -1.2954 0.5842)
			(stroke
				(width 0.1524)
				(type default)
			)
			(layer "F.SilkS")
		)
		(fp_line
			(start -1.2954 -0.5842)
			(end 1.2954 -0.5842)
			(stroke
				(width 0.1524)
				(type default)
			)
			(layer "F.SilkS")
		)
		(fp_line
			(start 1.2954 -0.5842)
			(end 1.2954 0.5842)
			(stroke
				(width 0.1524)
				(type default)
			)
			(layer "F.SilkS")
		)
		(fp_line
			(start -0.8636 0.4572)
			(end -0.8636 0.4318)
			(stroke
				(width 0.1)
				(type default)
			)
			(layer "F.Fab")
		)
		(fp_line
			(start 0.8636 0.4572)
			(end -0.8636 0.4572)
			(stroke
				(width 0.1)
				(type default)
			)
			(layer "F.Fab")
		)
		(fp_line
			(start -0.8636 0.4318)
			(end -0.8636 0.4064)
			(stroke
				(width 0.1)
				(type default)
			)
			(layer "F.Fab")
		)
		(fp_line
			(start -1.1938 0.4064)
			(end -1.1938 -0.406654)
			(stroke
				(width 0.1)
				(type default)
			)
			(layer "F.Fab")
		)
		(fp_line
			(start -0.8636 0.4064)
			(end -1.1938 0.4064)
			(stroke
				(width 0.1)
				(type default)
			)
			(layer "F.Fab")
		)
		(fp_line
			(start 0.8636 0.4064)
			(end 0.8636 0.4572)
			(stroke
				(width 0.1)
				(type default)
			)
			(layer "F.Fab")
		)
		(fp_line
			(start 1.1938 0.4064)
			(end 0.8636 0.4064)
			(stroke
				(width 0.1)
				(type default)
			)
			(layer "F.Fab")
		)
		(fp_line
			(start -1.1938 -0.406654)
			(end -0.8636 -0.406654)
			(stroke
				(width 0.1)
				(type default)
			)
			(layer "F.Fab")
		)
		(fp_line
			(start -0.8636 -0.406654)
			(end -0.8636 -0.4572)
			(stroke
				(width 0.1)
				(type default)
			)
			(layer "F.Fab")
		)
		(fp_line
			(start 0.8636 -0.406654)
			(end 1.1938 -0.406654)
			(stroke
				(width 0.1)
				(type default)
			)
			(layer "F.Fab")
		)
		(fp_line
			(start 1.1938 -0.406654)
			(end 1.1938 0.4064)
			(stroke
				(width 0.1)
				(type default)
			)
			(layer "F.Fab")
		)
		(fp_line
			(start -0.8636 -0.4572)
			(end 0.8636 -0.4572)
			(stroke
				(width 0.1)
				(type default)
			)
			(layer "F.Fab")
		)
		(fp_line
			(start 0.8636 -0.4572)
			(end 0.8636 -0.406654)
			(stroke
				(width 0.1)
				(type default)
			)
			(layer "F.Fab")
		)
		(pad "1" smd rect
			(at -0.7366 0 180)
			(size 0.7112 0.8128)
			(layers "F.Cu" "F.Mask" "F.Paste")
			(net "P52V_HS1_GATE2_R")
		)
		(pad "2" smd rect
			(at 0.7366 0 180)
			(size 0.7112 0.8128)
			(layers "F.Cu" "F.Mask" "F.Paste")
			(net "P52V_HS1_GATE4")
		)
	)
	(footprint ""
		(layer "F.Cu")
		(at 406.146 -40.132)
		(property "Reference" "R38"
			(at 0 0 0)
			(layer "F.SilkS")
			(hide yes)
			(effects
				(font
					(size 1.27 1.27)
				)
			)
		)
		(property "Value" ""
			(at 0 0 0)
			(layer "F.Fab")
			(effects
				(font
					(size 1.27 1.27)
				)
			)
		)
		(duplicate_pad_numbers_are_jumpers no)
		(fp_line
			(start -2.234946 -0.9271)
			(end 2.234946 -0.9271)
			(stroke
				(width 0.1524)
				(type default)
			)
			(layer "F.SilkS")
		)
		(fp_line
			(start -2.234946 0.9271)
			(end -2.234946 -0.9271)
			(stroke
				(width 0.1524)
				(type default)
			)
			(layer "F.SilkS")
		)
		(fp_line
			(start 2.234946 -0.9271)
			(end 2.234946 0.9271)
			(stroke
				(width 0.1524)
				(type default)
			)
			(layer "F.SilkS")
		)
		(fp_line
			(start 2.234946 0.9271)
			(end -2.234946 0.9271)
			(stroke
				(width 0.1524)
				(type default)
			)
			(layer "F.SilkS")
		)
		(fp_line
			(start -1.575054 -0.824992)
			(end -1.575054 0.824992)
			(stroke
				(width 0.1)
				(type default)
			)
			(layer "F.Fab")
		)
		(fp_line
			(start -1.575054 0.824992)
			(end 1.575054 0.824992)
			(stroke
				(width 0.1)
				(type default)
			)
			(layer "F.Fab")
		)
		(fp_line
			(start 1.575054 -0.824992)
			(end -1.575054 -0.824992)
			(stroke
				(width 0.1)
				(type default)
			)
			(layer "F.Fab")
		)
		(fp_line
			(start 1.575054 0.824992)
			(end 1.575054 -0.824992)
			(stroke
				(width 0.1)
				(type default)
			)
			(layer "F.Fab")
		)
		(pad "1" smd rect
			(at -1.599946 0)
			(size 1.016 1.6002)
			(layers "F.Cu" "F.Mask" "F.Paste")
			(net "P52V_HS1")
		)
		(pad "2" smd rect
			(at 1.599946 0)
			(size 1.016 1.6002)
			(layers "F.Cu" "F.Mask" "F.Paste")
			(net "LED_D1_R1")
		)
	)
)
